# TIMECARD (Time Appliance Project (Time Card)) — schematic netlist excerpt (pin names and nets, part order shuffled) for the footprints in the layout excerpt that follows; sources: Cadence DE-HDL packaged netlist, KiCad conversion of R4006-B0001-02_R01.brd

C303  CAPACITOR  10UF 25V 20%  pkg SMC_0805R_H057  page 27 : \1\ = XP12R0V_IN ; \2\ = SG
C147  CAPACITOR  0.1UF 10V 10%  pkg SMC_0402R_H022  page 14 : \1\ = XP1R0V_FPGA_VCCINT ; \2\ = SG

(kicad_pcb
	(version 20260206)
	(generator "pcbnew")
	(generator_version "10.0")
	(general
		(thickness 1.6)
		(legacy_teardrops no)
	)
	(paper "A4")
	(title_block
		(title "timecard-production-celestica-r4006 — R4006-B0001-02_R01.brd")
		(comment 1 "Time Appliance Project (Time Card) / footprints 837-838 of 1113")
	)
	(layers
		(0 "F.Cu" signal "TOP")
		(4 "In1.Cu" signal "L02_GND1")
		(6 "In2.Cu" signal "L03_SIG1")
		(8 "In3.Cu" signal "L04_GND2")
		(10 "In4.Cu" signal "L05_VCC1")
		(12 "In5.Cu" signal "L06_VCC2")
		(14 "In6.Cu" signal "L07_GND3")
		(16 "In7.Cu" signal "L08_SIG2")
		(18 "In8.Cu" signal "L09_GND4")
		(2 "B.Cu" signal "BOTTOM")
		(9 "F.Adhes" user "F.Adhesive")
		(11 "B.Adhes" user "B.Adhesive")
		(13 "F.Paste" user "Package Geometry/Pastemask Top")
		(15 "B.Paste" user "Package Geometry/Pastemask Bottom")
		(5 "F.SilkS" user "Ref Des/Silkscreen Top")
		(7 "B.SilkS" user "Ref Des/Silkscreen Bottom")
		(1 "F.Mask" user "Board Geometry/Soldermask Top")
		(3 "B.Mask" user "Board Geometry/Soldermask Bottom")
		(17 "Dwgs.User" user "User.Drawings")
		(19 "Cmts.User" user "User.Comments")
		(21 "Eco1.User" user "User.Eco1")
		(23 "Eco2.User" user "User.Eco2")
		(25 "Edge.Cuts" user "Board Geometry/Outline")
		(27 "Margin" user)
		(31 "F.CrtYd" user "Package Geometry/Place Bound Top")
		(29 "B.CrtYd" user "Package Geometry/Place Bound Bottom")
		(35 "F.Fab" user "Ref Des/Assembly Top")
		(33 "B.Fab" user "Ref Des/Assembly Bottom")
	)
	(footprint ""
		(layer "B.Cu")
		(at 139.5476 -81.4324)
		(property "Reference" "C303"
			(at 0.6604 -7.68223 0)
			(unlocked yes)
			(layer "B.SilkS")
			(effects
				(font
					(size 0.7874 0.5842)
					(thickness 0.1524)
				)
				(justify mirror)
			)
		)
		(property "Value" "VAL*"
			(at -0.0762 3.134106 0)
			(unlocked yes)
			(layer "B.Fab")
			(hide yes)
			(effects
				(font
					(size 0.7874 0.5842)
					(thickness 0.1524)
				)
				(justify mirror)
			)
		)
		(property "Device Type" "CAPACITOR-G107-0F106-EM,10UF,2A"
			(at -0.0508 2.194306 0)
			(unlocked yes)
			(layer "B.Fab")
			(hide yes)
			(effects
				(font
					(size 0.7874 0.5842)
					(thickness 0.1524)
				)
				(justify mirror)
			)
		)
		(property "User Part Number" "PARTNUM*"
			(at -0.1016 5.013706 0)
			(unlocked yes)
			(layer "Cmts.User")
			(hide yes)
			(effects
				(font
					(size 0.7874 0.5842)
					(thickness 0.1524)
				)
				(justify mirror)
			)
		)
		(property "Tolerance" "TOL*"
			(at -0.0762 4.048506 0)
			(unlocked yes)
			(layer "Cmts.User")
			(hide yes)
			(effects
				(font
					(size 0.7874 0.5842)
					(thickness 0.1524)
				)
				(justify mirror)
			)
		)
		(duplicate_pad_numbers_are_jumpers no)
		(fp_line
			(start -1.5748 -0.9398)
			(end 1.5748 -0.9398)
			(stroke
				(width 0.1)
				(type default)
			)
			(layer "B.SilkS")
		)
		(fp_line
			(start -1.5748 0.9398)
			(end -1.5748 -0.9398)
			(stroke
				(width 0.1)
				(type default)
			)
			(layer "B.SilkS")
		)
		(fp_line
			(start 1.5748 -0.9398)
			(end 1.5748 0.9398)
			(stroke
				(width 0.1)
				(type default)
			)
			(layer "B.SilkS")
		)
		(fp_line
			(start 1.5748 0.9398)
			(end -1.5748 0.9398)
			(stroke
				(width 0.1)
				(type default)
			)
			(layer "B.SilkS")
		)
		(fp_rect
			(start 1.5748 0.9398)
			(end -1.5748 -0.9398)
			(stroke
				(width 0)
				(type default)
			)
			(fill no)
			(layer "B.CrtYd")
		)
		(fp_line
			(start -1.016 -0.635)
			(end 1.016 -0.635)
			(stroke
				(width 0.1)
				(type default)
			)
			(layer "B.Fab")
		)
		(fp_line
			(start -1.016 0.635)
			(end -1.016 -0.635)
			(stroke
				(width 0.1)
				(type default)
			)
			(layer "B.Fab")
		)
		(fp_line
			(start 1.016 -0.635)
			(end 1.016 0.635)
			(stroke
				(width 0.1)
				(type default)
			)
			(layer "B.Fab")
		)
		(fp_line
			(start 1.016 0.635)
			(end -1.016 0.635)
			(stroke
				(width 0.1)
				(type default)
			)
			(layer "B.Fab")
		)
		(pad "1" smd rect
			(at 0.8382 0 180)
			(size 0.9652 1.3716)
			(layers "B.Cu" "B.Mask" "B.Paste")
			(net "XP12R0V_IN")
		)
		(pad "2" smd rect
			(at -0.8382 0 180)
			(size 0.9652 1.3716)
			(layers "B.Cu" "B.Mask" "B.Paste")
			(net "SG")
		)
		(zone
			(layer "B.Cu")
			(hatch none 0.5)
			(connect_pads
				(clearance 0)
			)
			(min_thickness 0.25)
			(keepout
				(tracks allowed)
				(vias not_allowed)
				(pads allowed)
				(copperpour not_allowed)
				(footprints allowed)
			)
			(placement
				(enabled no)
				(sheetname "")
			)
			(fill
				(thermal_gap 0.5)
				(thermal_bridge_width 0.5)
				(island_removal_mode 0)
			)
			(polygon
				(pts
					(xy 139.7762 -80.7974) (xy 139.7762 -82.0674) (xy 139.319 -82.0674) (xy 139.319 -80.7974)
				)
			)
		)
		(zone
			(layer "B.Cu")
			(hatch none 0.5)
			(connect_pads
				(clearance 0)
			)
			(min_thickness 0.25)
			(keepout
				(tracks not_allowed)
				(vias allowed)
				(pads allowed)
				(copperpour not_allowed)
				(footprints allowed)
			)
			(placement
				(enabled no)
				(sheetname "")
			)
			(fill
				(thermal_gap 0.5)
				(thermal_bridge_width 0.5)
				(island_removal_mode 0)
			)
			(polygon
				(pts
					(xy 139.7762 -80.7974) (xy 139.7762 -82.0674) (xy 139.319 -82.0674) (xy 139.319 -80.7974)
				)
			)
		)
	)
	(footprint ""
		(layer "B.Cu")
		(at 113.347246 -41.823132 180)
		(property "Reference" "C147"
			(at 41.909746 -1.250442 0)
			(unlocked yes)
			(layer "B.SilkS")
			(effects
				(font
					(size 0.635 0.4064)
					(thickness 0.1524)
				)
				(justify mirror)
			)
		)
		(property "Value" "VAL*"
			(at 0 3.718306 180)
			(unlocked yes)
			(layer "B.Fab")
			(hide yes)
			(effects
				(font
					(size 0.7874 0.5842)
					(thickness 0.127)
				)
				(justify mirror)
			)
		)
		(property "Device Type" "CAPACITOR-G105-0B104-CK,0.1UF,A"
			(at 0 1.432306 180)
			(unlocked yes)
			(layer "B.Fab")
			(hide yes)
			(effects
				(font
					(size 0.7874 0.5842)
					(thickness 0.127)
				)
				(justify mirror)
			)
		)
		(property "User Part Number" "PARTNUM*"
			(at 0 2.575306 180)
			(unlocked yes)
			(layer "Cmts.User")
			(hide yes)
			(effects
				(font
					(size 0.7874 0.5842)
					(thickness 0.127)
				)
				(justify mirror)
			)
		)
		(property "Tolerance" "TOL*"
			(at 0 4.861306 180)
			(unlocked yes)
			(layer "Cmts.User")
			(hide yes)
			(effects
				(font
					(size 0.7874 0.5842)
					(thickness 0.127)
				)
				(justify mirror)
			)
		)
		(duplicate_pad_numbers_are_jumpers no)
		(fp_line
			(start 0.970026 0.4699)
			(end 0.970026 -0.4699)
			(stroke
				(width 0.1)
				(type default)
			)
			(layer "B.SilkS")
		)
		(fp_line
			(start 0.970026 -0.4699)
			(end -0.970026 -0.4699)
			(stroke
				(width 0.1)
				(type default)
			)
			(layer "B.SilkS")
		)
		(fp_line
			(start -0.970026 0.4699)
			(end 0.970026 0.4699)
			(stroke
				(width 0.1)
				(type default)
			)
			(layer "B.SilkS")
		)
		(fp_line
			(start -0.970026 -0.4699)
			(end -0.970026 0.4699)
			(stroke
				(width 0.1)
				(type default)
			)
			(layer "B.SilkS")
		)
		(fp_poly
			(pts
				(xy 0.970026 0.4699) (xy -0.970026 0.4699) (xy -0.970026 -0.4699) (xy 0.970026 -0.4699)
			)
			(stroke
				(width 0)
				(type default)
			)
			(fill no)
			(layer "B.CrtYd")
		)
		(fp_line
			(start 0.508 0.3048)
			(end 0.508 -0.3048)
			(stroke
				(width 0.1)
				(type default)
			)
			(layer "B.Fab")
		)
		(fp_line
			(start 0.508 -0.3048)
			(end -0.508 -0.3048)
			(stroke
				(width 0.1)
				(type default)
			)
			(layer "B.Fab")
		)
		(fp_line
			(start -0.508 0.3048)
			(end 0.508 0.3048)
			(stroke
				(width 0.1)
				(type default)
			)
			(layer "B.Fab")
		)
		(fp_line
			(start -0.508 -0.3048)
			(end -0.508 0.3048)
			(stroke
				(width 0.1)
				(type default)
			)
			(layer "B.Fab")
		)
		(pad "1" smd circle
			(at 0.500126 0)
			(size 0.635 0.635)
			(layers "B.Cu" "B.Mask" "B.Paste")
			(net "XP1R0V_FPGA_VCCINT")
		)
		(pad "2" smd circle
			(at -0.500126 0)
			(size 0.635 0.635)
			(layers "B.Cu" "B.Mask" "B.Paste")
			(net "SG")
		)
	)
)
